# S9S_MB_2U (Grand Teton) — schematic netlist excerpt (pin names and nets, part order shuffled) for the footprints in the layout excerpt that follows; sources: Cadence DE-HDL packaged netlist, KiCad conversion of 03242023_DA0F0TMBIJ0_F0T_Motherboard_J_brd_V01_OCP.brd

PC186  Q_CAP  22UF 4V 20% X6S  pkg C0805  page 276 : A = PVCCFA_EHV_CPU0 ; B = GND
PR3927  Q_RES  4.99K 0.1% CHIP  pkg 0402LF  page 301 : A = HSC_VSENSE ; B = AGND_HSC
C1928  Q_CAP  0.01UF 50V 10% X7R  pkg C0402  page 217 : A = VCC_PLD_CORE ; B = GND

(kicad_pcb
	(version 20260206)
	(generator "pcbnew")
	(generator_version "10.0")
	(general
		(thickness 1.6)
		(legacy_teardrops no)
	)
	(paper "A4")
	(title_block
		(title "03242023_DA0F0TMBIJ0_F0T_Motherboard_J_brd_V01_OCP.brd")
		(comment 1 "Grand Teton / footprints 4844-4846 of 6105")
	)
	(layers
		(0 "F.Cu" signal "TOP")
		(4 "In1.Cu" signal "GND")
		(6 "In2.Cu" signal "IN1")
		(8 "In3.Cu" signal "GND1")
		(10 "In4.Cu" signal "IN2")
		(12 "In5.Cu" signal "GND2")
		(14 "In6.Cu" signal "IN3")
		(16 "In7.Cu" signal "GND3")
		(18 "In8.Cu" signal "VCC")
		(20 "In9.Cu" signal "VCC1")
		(22 "In10.Cu" signal "GND4")
		(24 "In11.Cu" signal "IN4")
		(26 "In12.Cu" signal "GND5")
		(28 "In13.Cu" signal "IN5")
		(30 "In14.Cu" signal "GND6")
		(32 "In15.Cu" signal "IN6")
		(34 "In16.Cu" signal "GND7")
		(2 "B.Cu" signal "BOTTOM")
		(9 "F.Adhes" user "F.Adhesive")
		(11 "B.Adhes" user "B.Adhesive")
		(13 "F.Paste" user "Package Geometry/Pastemask Top")
		(15 "B.Paste" user "Package Geometry/Pastemask Bottom")
		(5 "F.SilkS" user "Ref Des/Silkscreen Top")
		(7 "B.SilkS" user "Ref Des/Silkscreen Bottom")
		(1 "F.Mask" user "Board Geometry/Soldermask Top")
		(3 "B.Mask" user "Board Geometry/Soldermask Bottom")
		(17 "Dwgs.User" user "User.Drawings")
		(19 "Cmts.User" user "User.Comments")
		(21 "Eco1.User" user "User.Eco1")
		(23 "Eco2.User" user "User.Eco2")
		(25 "Edge.Cuts" user "Board Geometry/Outline")
		(27 "Margin" user)
		(31 "F.CrtYd" user "Package Geometry/Place Bound Top")
		(29 "B.CrtYd" user "Package Geometry/Place Bound Bottom")
		(35 "F.Fab" user "Ref Des/Assembly Top")
		(33 "B.Fab" user "Ref Des/Assembly Bottom")
	)
	(footprint ""
		(layer "B.Cu")
		(at 178.9557 -112.57534 90)
		(property "Reference" "C1928"
			(at 0 0 90)
			(layer "B.SilkS")
			(hide yes)
			(effects
				(font
					(size 1.27 1.27)
				)
				(justify mirror)
			)
		)
		(property "Value" ""
			(at 0 0 90)
			(layer "B.Fab")
			(effects
				(font
					(size 1.27 1.27)
				)
				(justify mirror)
			)
		)
		(duplicate_pad_numbers_are_jumpers no)
		(fp_line
			(start 0.69215 -0.2921)
			(end -0.69215 -0.2921)
			(stroke
				(width 0.1524)
				(type default)
			)
			(layer "B.SilkS")
		)
		(fp_line
			(start -0.69215 -0.2921)
			(end -0.69215 0.2921)
			(stroke
				(width 0.1524)
				(type default)
			)
			(layer "B.SilkS")
		)
		(fp_line
			(start 0.69215 0.2921)
			(end 0.69215 -0.2921)
			(stroke
				(width 0.1524)
				(type default)
			)
			(layer "B.SilkS")
		)
		(fp_line
			(start -0.69215 0.2921)
			(end 0.69215 0.2921)
			(stroke
				(width 0.1524)
				(type default)
			)
			(layer "B.SilkS")
		)
		(fp_line
			(start 0.51435 -0.2794)
			(end -0.51435 -0.2794)
			(stroke
				(width 0.1)
				(type default)
			)
			(layer "B.Fab")
		)
		(fp_line
			(start -0.51435 -0.2794)
			(end -0.51435 0.2794)
			(stroke
				(width 0.1)
				(type default)
			)
			(layer "B.Fab")
		)
		(fp_line
			(start 0.51435 0.2794)
			(end 0.51435 -0.2794)
			(stroke
				(width 0.1)
				(type default)
			)
			(layer "B.Fab")
		)
		(fp_line
			(start -0.51435 0.2794)
			(end 0.51435 0.2794)
			(stroke
				(width 0.1)
				(type default)
			)
			(layer "B.Fab")
		)
		(pad "1" smd circle
			(at 0.40005 0 270)
			(size 0 0)
			(layers "B.Cu" "B.Mask" "B.Paste")
			(net "VCC_PLD_CORE")
		)
		(pad "2" smd circle
			(at -0.40005 0 270)
			(size 0 0)
			(layers "B.Cu" "B.Mask" "B.Paste")
			(net "GND")
		)
		(zone
			(layer "B.Cu")
			(hatch none 0.5)
			(connect_pads
				(clearance 0)
			)
			(min_thickness 0.25)
			(keepout
				(tracks not_allowed)
				(vias allowed)
				(pads allowed)
				(copperpour not_allowed)
				(footprints allowed)
			)
			(placement
				(enabled no)
				(sheetname "")
			)
			(fill
				(thermal_gap 0.5)
				(thermal_bridge_width 0.5)
				(island_removal_mode 0)
			)
			(polygon
				(pts
					(xy 179.04333 -112.76584) (xy 179.101496 -112.6744) (xy 179.101496 -112.47501) (xy 179.04333 -112.38484)
					(xy 178.86807 -112.38484) (xy 178.80965 -112.47501) (xy 178.80965 -112.6744) (xy 178.867816 -112.76584)
				)
			)
		)
	)
	(footprint ""
		(layer "B.Cu")
		(at 183.995568 -407.863802 -90)
		(property "Reference" "PR3927"
			(at 0 0 90)
			(layer "B.SilkS")
			(hide yes)
			(effects
				(font
					(size 1.27 1.27)
				)
				(justify mirror)
			)
		)
		(property "Value" ""
			(at 0 0 90)
			(layer "B.Fab")
			(effects
				(font
					(size 1.27 1.27)
				)
				(justify mirror)
			)
		)
		(duplicate_pad_numbers_are_jumpers no)
		(fp_line
			(start -0.7874 0.4064)
			(end 0.7874 0.4064)
			(stroke
				(width 0.1524)
				(type default)
			)
			(layer "B.SilkS")
		)
		(fp_line
			(start 0.7874 0.4064)
			(end 0.7874 -0.4064)
			(stroke
				(width 0.1524)
				(type default)
			)
			(layer "B.SilkS")
		)
		(fp_line
			(start -0.7874 -0.4064)
			(end -0.7874 0.4064)
			(stroke
				(width 0.1524)
				(type default)
			)
			(layer "B.SilkS")
		)
		(fp_line
			(start 0.7874 -0.4064)
			(end -0.7874 -0.4064)
			(stroke
				(width 0.1524)
				(type default)
			)
			(layer "B.SilkS")
		)
		(fp_line
			(start -0.67945 0.3048)
			(end -0.120396 0.3048)
			(stroke
				(width 0.1)
				(type default)
			)
			(layer "B.Fab")
		)
		(fp_line
			(start -0.120396 0.3048)
			(end -0.120396 0.2794)
			(stroke
				(width 0.1)
				(type default)
			)
			(layer "B.Fab")
		)
		(fp_line
			(start 0.12065 0.3048)
			(end 0.67945 0.3048)
			(stroke
				(width 0.1)
				(type default)
			)
			(layer "B.Fab")
		)
		(fp_line
			(start 0.67945 0.3048)
			(end 0.67945 -0.305054)
			(stroke
				(width 0.1)
				(type default)
			)
			(layer "B.Fab")
		)
		(fp_line
			(start -0.120396 0.2794)
			(end 0.12065 0.2794)
			(stroke
				(width 0.1)
				(type default)
			)
			(layer "B.Fab")
		)
		(fp_line
			(start 0.12065 0.2794)
			(end 0.12065 0.3048)
			(stroke
				(width 0.1)
				(type default)
			)
			(layer "B.Fab")
		)
		(fp_line
			(start -0.12065 -0.2794)
			(end -0.12065 -0.3048)
			(stroke
				(width 0.1)
				(type default)
			)
			(layer "B.Fab")
		)
		(fp_line
			(start 0.12065 -0.2794)
			(end -0.12065 -0.2794)
			(stroke
				(width 0.1)
				(type default)
			)
			(layer "B.Fab")
		)
		(fp_line
			(start -0.67945 -0.3048)
			(end -0.67945 0.3048)
			(stroke
				(width 0.1)
				(type default)
			)
			(layer "B.Fab")
		)
		(fp_line
			(start -0.12065 -0.3048)
			(end -0.67945 -0.3048)
			(stroke
				(width 0.1)
				(type default)
			)
			(layer "B.Fab")
		)
		(fp_line
			(start 0.12065 -0.305054)
			(end 0.12065 -0.2794)
			(stroke
				(width 0.1)
				(type default)
			)
			(layer "B.Fab")
		)
		(fp_line
			(start 0.67945 -0.305054)
			(end 0.12065 -0.305054)
			(stroke
				(width 0.1)
				(type default)
			)
			(layer "B.Fab")
		)
		(pad "1" smd circle
			(at 0.40005 0 90)
			(size 0 0)
			(layers "B.Cu" "B.Mask" "B.Paste")
			(net "HSC_VSENSE")
		)
		(pad "2" smd circle
			(at -0.40005 0 90)
			(size 0 0)
			(layers "B.Cu" "B.Mask" "B.Paste")
			(net "AGND_HSC")
		)
	)
	(footprint ""
		(layer "B.Cu")
		(at 409.30957 -149.65299 180)
		(property "Reference" "PC186"
			(at 0 0 0)
			(layer "B.SilkS")
			(hide yes)
			(effects
				(font
					(size 1.27 1.27)
				)
				(justify mirror)
			)
		)
		(property "Value" ""
			(at 0 0 0)
			(layer "B.Fab")
			(effects
				(font
					(size 1.27 1.27)
				)
				(justify mirror)
			)
		)
		(duplicate_pad_numbers_are_jumpers no)
		(fp_line
			(start 1.524 0.762)
			(end 1.524 -0.762)
			(stroke
				(width 0.1524)
				(type default)
			)
			(layer "B.SilkS")
		)
		(fp_line
			(start 1.524 -0.762)
			(end -1.524 -0.762)
			(stroke
				(width 0.1524)
				(type default)
			)
			(layer "B.SilkS")
		)
		(fp_line
			(start -1.524 0.762)
			(end 1.524 0.762)
			(stroke
				(width 0.1524)
				(type default)
			)
			(layer "B.SilkS")
		)
		(fp_line
			(start -1.524 -0.762)
			(end -1.524 0.762)
			(stroke
				(width 0.1524)
				(type default)
			)
			(layer "B.SilkS")
		)
		(fp_line
			(start 1.1049 0.724916)
			(end -1.1049 0.724916)
			(stroke
				(width 0.1)
				(type default)
			)
			(layer "B.Fab")
		)
		(fp_line
			(start 1.1049 -0.724916)
			(end 1.1049 0.724916)
			(stroke
				(width 0.1)
				(type default)
			)
			(layer "B.Fab")
		)
		(fp_line
			(start -1.1049 0.724916)
			(end -1.1049 -0.724916)
			(stroke
				(width 0.1)
				(type default)
			)
			(layer "B.Fab")
		)
		(fp_line
			(start -1.1049 -0.724916)
			(end 1.1049 -0.724916)
			(stroke
				(width 0.1)
				(type default)
			)
			(layer "B.Fab")
		)
		(pad "1" smd rect
			(at 0.889 0 180)
			(size 1.016 1.27)
			(layers "B.Cu" "B.Mask" "B.Paste")
			(net "PVCCFA_EHV_CPU0")
		)
		(pad "2" smd rect
			(at -0.889 0 180)
			(size 1.016 1.27)
			(layers "B.Cu" "B.Mask" "B.Paste")
			(net "GND")
		)
	)
)
